# S9S_MB_2U (Grand Teton) — schematic netlist excerpt (pin names and nets, part order shuffled) for the footprints in the layout excerpt that follows; sources: Cadence DE-HDL packaged netlist, KiCad conversion of 03242023_DA0F0TMBIJ0_F0T_Motherboard_J_brd_V01_OCP.brd

R2990  Q_RES  33.2 1% CHIP  pkg 0402LF  page 234 : A = SMB_2_BMC_GPU_BUF_R_SCL ; B = SMB_2_BMC_GPU_BUF_SCL
R2315  Q_RES  10K 1% CHIP  pkg 0402LF  page 236 : A = P3V3_AUX ; B = PCA9543_S3M_INT0_N

(kicad_pcb
	(version 20260206)
	(generator "pcbnew")
	(generator_version "10.0")
	(general
		(thickness 1.6)
		(legacy_teardrops no)
	)
	(paper "A4")
	(title_block
		(title "03242023_DA0F0TMBIJ0_F0T_Motherboard_J_brd_V01_OCP.brd")
		(comment 1 "Grand Teton / footprints 3379-3380 of 6105")
	)
	(layers
		(0 "F.Cu" signal "TOP")
		(4 "In1.Cu" signal "GND")
		(6 "In2.Cu" signal "IN1")
		(8 "In3.Cu" signal "GND1")
		(10 "In4.Cu" signal "IN2")
		(12 "In5.Cu" signal "GND2")
		(14 "In6.Cu" signal "IN3")
		(16 "In7.Cu" signal "GND3")
		(18 "In8.Cu" signal "VCC")
		(20 "In9.Cu" signal "VCC1")
		(22 "In10.Cu" signal "GND4")
		(24 "In11.Cu" signal "IN4")
		(26 "In12.Cu" signal "GND5")
		(28 "In13.Cu" signal "IN5")
		(30 "In14.Cu" signal "GND6")
		(32 "In15.Cu" signal "IN6")
		(34 "In16.Cu" signal "GND7")
		(2 "B.Cu" signal "BOTTOM")
		(9 "F.Adhes" user "F.Adhesive")
		(11 "B.Adhes" user "B.Adhesive")
		(13 "F.Paste" user "Package Geometry/Pastemask Top")
		(15 "B.Paste" user "Package Geometry/Pastemask Bottom")
		(5 "F.SilkS" user "Ref Des/Silkscreen Top")
		(7 "B.SilkS" user "Ref Des/Silkscreen Bottom")
		(1 "F.Mask" user "Board Geometry/Soldermask Top")
		(3 "B.Mask" user "Board Geometry/Soldermask Bottom")
		(17 "Dwgs.User" user "User.Drawings")
		(19 "Cmts.User" user "User.Comments")
		(21 "Eco1.User" user "User.Eco1")
		(23 "Eco2.User" user "User.Eco2")
		(25 "Edge.Cuts" user "Board Geometry/Outline")
		(27 "Margin" user)
		(31 "F.CrtYd" user "Package Geometry/Place Bound Top")
		(29 "B.CrtYd" user "Package Geometry/Place Bound Bottom")
		(35 "F.Fab" user "Ref Des/Assembly Top")
		(33 "B.Fab" user "Ref Des/Assembly Bottom")
	)
	(footprint ""
		(layer "F.Cu")
		(at 162.34283 -74.759058 180)
		(property "Reference" "R2315"
			(at 0 0 180)
			(layer "F.SilkS")
			(hide yes)
			(effects
				(font
					(size 1.27 1.27)
				)
			)
		)
		(property "Value" ""
			(at 0 0 180)
			(layer "F.Fab")
			(effects
				(font
					(size 1.27 1.27)
				)
			)
		)
		(duplicate_pad_numbers_are_jumpers no)
		(fp_line
			(start 0.7874 0.4064)
			(end -0.7874 0.4064)
			(stroke
				(width 0.1524)
				(type default)
			)
			(layer "F.SilkS")
		)
		(fp_line
			(start 0.7874 -0.4064)
			(end 0.7874 0.4064)
			(stroke
				(width 0.1524)
				(type default)
			)
			(layer "F.SilkS")
		)
		(fp_line
			(start -0.7874 0.4064)
			(end -0.7874 -0.4064)
			(stroke
				(width 0.1524)
				(type default)
			)
			(layer "F.SilkS")
		)
		(fp_line
			(start -0.7874 -0.4064)
			(end 0.7874 -0.4064)
			(stroke
				(width 0.1524)
				(type default)
			)
			(layer "F.SilkS")
		)
		(fp_line
			(start 0.67945 0.3048)
			(end 0.120396 0.3048)
			(stroke
				(width 0.1)
				(type default)
			)
			(layer "F.Fab")
		)
		(fp_line
			(start 0.67945 -0.3048)
			(end 0.67945 0.3048)
			(stroke
				(width 0.1)
				(type default)
			)
			(layer "F.Fab")
		)
		(fp_line
			(start 0.12065 -0.2794)
			(end 0.12065 -0.3048)
			(stroke
				(width 0.1)
				(type default)
			)
			(layer "F.Fab")
		)
		(fp_line
			(start 0.12065 -0.3048)
			(end 0.67945 -0.3048)
			(stroke
				(width 0.1)
				(type default)
			)
			(layer "F.Fab")
		)
		(fp_line
			(start 0.120396 0.3048)
			(end 0.120396 0.2794)
			(stroke
				(width 0.1)
				(type default)
			)
			(layer "F.Fab")
		)
		(fp_line
			(start 0.120396 0.2794)
			(end -0.12065 0.2794)
			(stroke
				(width 0.1)
				(type default)
			)
			(layer "F.Fab")
		)
		(fp_line
			(start -0.12065 0.3048)
			(end -0.67945 0.3048)
			(stroke
				(width 0.1)
				(type default)
			)
			(layer "F.Fab")
		)
		(fp_line
			(start -0.12065 0.2794)
			(end -0.12065 0.3048)
			(stroke
				(width 0.1)
				(type default)
			)
			(layer "F.Fab")
		)
		(fp_line
			(start -0.12065 -0.2794)
			(end 0.12065 -0.2794)
			(stroke
				(width 0.1)
				(type default)
			)
			(layer "F.Fab")
		)
		(fp_line
			(start -0.12065 -0.305054)
			(end -0.12065 -0.2794)
			(stroke
				(width 0.1)
				(type default)
			)
			(layer "F.Fab")
		)
		(fp_line
			(start -0.67945 0.3048)
			(end -0.67945 -0.305054)
			(stroke
				(width 0.1)
				(type default)
			)
			(layer "F.Fab")
		)
		(fp_line
			(start -0.67945 -0.305054)
			(end -0.12065 -0.305054)
			(stroke
				(width 0.1)
				(type default)
			)
			(layer "F.Fab")
		)
		(pad "1" smd circle
			(at -0.40005 0 180)
			(size 0 0)
			(layers "F.Cu" "F.Mask" "F.Paste")
			(net "P3V3_AUX")
		)
		(pad "2" smd circle
			(at 0.40005 0 180)
			(size 0 0)
			(layers "F.Cu" "F.Mask" "F.Paste")
			(net "PCA9543_S3M_INT0_N")
		)
	)
	(footprint ""
		(layer "F.Cu")
		(at 46.626018 -437.792368)
		(property "Reference" "R2990"
			(at 0 0 0)
			(layer "F.SilkS")
			(hide yes)
			(effects
				(font
					(size 1.27 1.27)
				)
			)
		)
		(property "Value" ""
			(at 0 0 0)
			(layer "F.Fab")
			(effects
				(font
					(size 1.27 1.27)
				)
			)
		)
		(duplicate_pad_numbers_are_jumpers no)
		(fp_line
			(start -0.7874 -0.4064)
			(end 0.7874 -0.4064)
			(stroke
				(width 0.1524)
				(type default)
			)
			(layer "F.SilkS")
		)
		(fp_line
			(start -0.7874 0.4064)
			(end -0.7874 -0.4064)
			(stroke
				(width 0.1524)
				(type default)
			)
			(layer "F.SilkS")
		)
		(fp_line
			(start 0.7874 -0.4064)
			(end 0.7874 0.4064)
			(stroke
				(width 0.1524)
				(type default)
			)
			(layer "F.SilkS")
		)
		(fp_line
			(start 0.7874 0.4064)
			(end -0.7874 0.4064)
			(stroke
				(width 0.1524)
				(type default)
			)
			(layer "F.SilkS")
		)
		(fp_line
			(start -0.67945 -0.305054)
			(end -0.12065 -0.305054)
			(stroke
				(width 0.1)
				(type default)
			)
			(layer "F.Fab")
		)
		(fp_line
			(start -0.67945 0.3048)
			(end -0.67945 -0.305054)
			(stroke
				(width 0.1)
				(type default)
			)
			(layer "F.Fab")
		)
		(fp_line
			(start -0.12065 -0.305054)
			(end -0.12065 -0.2794)
			(stroke
				(width 0.1)
				(type default)
			)
			(layer "F.Fab")
		)
		(fp_line
			(start -0.12065 -0.2794)
			(end 0.12065 -0.2794)
			(stroke
				(width 0.1)
				(type default)
			)
			(layer "F.Fab")
		)
		(fp_line
			(start -0.12065 0.2794)
			(end -0.12065 0.3048)
			(stroke
				(width 0.1)
				(type default)
			)
			(layer "F.Fab")
		)
		(fp_line
			(start -0.12065 0.3048)
			(end -0.67945 0.3048)
			(stroke
				(width 0.1)
				(type default)
			)
			(layer "F.Fab")
		)
		(fp_line
			(start 0.120396 0.2794)
			(end -0.12065 0.2794)
			(stroke
				(width 0.1)
				(type default)
			)
			(layer "F.Fab")
		)
		(fp_line
			(start 0.120396 0.3048)
			(end 0.120396 0.2794)
			(stroke
				(width 0.1)
				(type default)
			)
			(layer "F.Fab")
		)
		(fp_line
			(start 0.12065 -0.3048)
			(end 0.67945 -0.3048)
			(stroke
				(width 0.1)
				(type default)
			)
			(layer "F.Fab")
		)
		(fp_line
			(start 0.12065 -0.2794)
			(end 0.12065 -0.3048)
			(stroke
				(width 0.1)
				(type default)
			)
			(layer "F.Fab")
		)
		(fp_line
			(start 0.67945 -0.3048)
			(end 0.67945 0.3048)
			(stroke
				(width 0.1)
				(type default)
			)
			(layer "F.Fab")
		)
		(fp_line
			(start 0.67945 0.3048)
			(end 0.120396 0.3048)
			(stroke
				(width 0.1)
				(type default)
			)
			(layer "F.Fab")
		)
		(pad "1" smd circle
			(at -0.40005 0)
			(size 0 0)
			(layers "F.Cu" "F.Mask" "F.Paste")
			(net "SMB_2_BMC_GPU_BUF_R_SCL")
		)
		(pad "2" smd circle
			(at 0.40005 0)
			(size 0 0)
			(layers "F.Cu" "F.Mask" "F.Paste")
			(net "SMB_2_BMC_GPU_BUF_SCL")
		)
	)
)
